(kicad_pcb
	(version 20260206)
	(generator "pcbnew")
	(generator_version "10.0")
	(general
		(thickness 1.6)
		(legacy_teardrops no)
	)
	(paper "A4")
	(title_block
		(title "12092022_DA0F0TFB6D0_F0T_FAN_BOARD_MP5048_D_brd_v02_OCP.brd")
		(comment 1 "Grand Teton / footprints 805-811 of 924")
	)
	(layers
		(0 "F.Cu" signal "TOP")
		(4 "In1.Cu" signal "GND")
		(6 "In2.Cu" signal "IN1")
		(8 "In3.Cu" signal "IN2")
		(10 "In4.Cu" signal "GND1")
		(2 "B.Cu" signal "BOTTOM")
		(9 "F.Adhes" user "F.Adhesive")
		(11 "B.Adhes" user "B.Adhesive")
		(13 "F.Paste" user "Package Geometry/Pastemask Top")
		(15 "B.Paste" user "Package Geometry/Pastemask Bottom")
		(5 "F.SilkS" user "Ref Des/Silkscreen Top")
		(7 "B.SilkS" user "Ref Des/Silkscreen Bottom")
		(1 "F.Mask" user "Board Geometry/Soldermask Top")
		(3 "B.Mask" user "Board Geometry/Soldermask Bottom")
		(17 "Dwgs.User" user "User.Drawings")
		(19 "Cmts.User" user "User.Comments")
		(21 "Eco1.User" user "User.Eco1")
		(23 "Eco2.User" user "User.Eco2")
		(25 "Edge.Cuts" user "Board Geometry/Outline")
		(27 "Margin" user)
		(31 "F.CrtYd" user "Package Geometry/Place Bound Top")
		(29 "B.CrtYd" user "Package Geometry/Place Bound Bottom")
		(35 "F.Fab" user "Ref Des/Assembly Top")
		(33 "B.Fab" user "Ref Des/Assembly Bottom")
	)
	(footprint ""
		(layer "B.Cu")
		(at 17.414494 -258.572 90)
		(property "Reference" "PC58"
			(at 0 0 90)
			(layer "B.SilkS")
			(hide yes)
			(effects
				(font
					(size 1.27 1.27)
				)
				(justify mirror)
			)
		)
		(property "Value" ""
			(at 0 0 90)
			(layer "B.Fab")
			(effects
				(font
					(size 1.27 1.27)
				)
				(justify mirror)
			)
		)
		(duplicate_pad_numbers_are_jumpers no)
		(fp_line
			(start 0.7874 -0.4064)
			(end -0.7874 -0.4064)
			(stroke
				(width 0.1524)
				(type default)
			)
			(layer "B.SilkS")
		)
		(fp_line
			(start -0.7874 -0.4064)
			(end -0.7874 0.4064)
			(stroke
				(width 0.1524)
				(type default)
			)
			(layer "B.SilkS")
		)
		(fp_line
			(start 0.7874 0.4064)
			(end 0.7874 -0.4064)
			(stroke
				(width 0.1524)
				(type default)
			)
			(layer "B.SilkS")
		)
		(fp_line
			(start -0.7874 0.4064)
			(end 0.7874 0.4064)
			(stroke
				(width 0.1524)
				(type default)
			)
			(layer "B.SilkS")
		)
		(fp_line
			(start 0.67945 -0.305054)
			(end 0.12065 -0.305054)
			(stroke
				(width 0.1)
				(type default)
			)
			(layer "B.Fab")
		)
		(fp_line
			(start 0.12065 -0.305054)
			(end 0.12065 -0.2794)
			(stroke
				(width 0.1)
				(type default)
			)
			(layer "B.Fab")
		)
		(fp_line
			(start -0.12065 -0.3048)
			(end -0.67945 -0.3048)
			(stroke
				(width 0.1)
				(type default)
			)
			(layer "B.Fab")
		)
		(fp_line
			(start -0.67945 -0.3048)
			(end -0.67945 0.3048)
			(stroke
				(width 0.1)
				(type default)
			)
			(layer "B.Fab")
		)
		(fp_line
			(start 0.12065 -0.2794)
			(end -0.12065 -0.2794)
			(stroke
				(width 0.1)
				(type default)
			)
			(layer "B.Fab")
		)
		(fp_line
			(start -0.12065 -0.2794)
			(end -0.12065 -0.3048)
			(stroke
				(width 0.1)
				(type default)
			)
			(layer "B.Fab")
		)
		(fp_line
			(start 0.12065 0.2794)
			(end 0.12065 0.3048)
			(stroke
				(width 0.1)
				(type default)
			)
			(layer "B.Fab")
		)
		(fp_line
			(start -0.120396 0.2794)
			(end 0.12065 0.2794)
			(stroke
				(width 0.1)
				(type default)
			)
			(layer "B.Fab")
		)
		(fp_line
			(start 0.67945 0.3048)
			(end 0.67945 -0.305054)
			(stroke
				(width 0.1)
				(type default)
			)
			(layer "B.Fab")
		)
		(fp_line
			(start 0.12065 0.3048)
			(end 0.67945 0.3048)
			(stroke
				(width 0.1)
				(type default)
			)
			(layer "B.Fab")
		)
		(fp_line
			(start -0.120396 0.3048)
			(end -0.120396 0.2794)
			(stroke
				(width 0.1)
				(type default)
			)
			(layer "B.Fab")
		)
		(fp_line
			(start -0.67945 0.3048)
			(end -0.120396 0.3048)
			(stroke
				(width 0.1)
				(type default)
			)
			(layer "B.Fab")
		)
		(pad "1" smd circle
			(at 0.40005 0 270)
			(size 0 0)
			(layers "B.Cu" "B.Mask" "B.Paste")
			(net "FAN_7_SS")
		)
		(pad "2" smd circle
			(at -0.40005 0 270)
			(size 0 0)
			(layers "B.Cu" "B.Mask" "B.Paste")
			(net "GND")
		)
	)
	(footprint ""
		(layer "B.Cu")
		(at 9.82599 -78.416912 90)
		(property "Reference" "PC62"
			(at 0 0 90)
			(layer "B.SilkS")
			(hide yes)
			(effects
				(font
					(size 1.27 1.27)
				)
				(justify mirror)
			)
		)
		(property "Value" ""
			(at 0 0 90)
			(layer "B.Fab")
			(effects
				(font
					(size 1.27 1.27)
				)
				(justify mirror)
			)
		)
		(duplicate_pad_numbers_are_jumpers no)
		(fp_line
			(start 1.524 -0.762)
			(end -1.524 -0.762)
			(stroke
				(width 0.1524)
				(type default)
			)
			(layer "B.SilkS")
		)
		(fp_line
			(start -1.524 -0.762)
			(end -1.524 0.762)
			(stroke
				(width 0.1524)
				(type default)
			)
			(layer "B.SilkS")
		)
		(fp_line
			(start 1.524 0.762)
			(end 1.524 -0.762)
			(stroke
				(width 0.1524)
				(type default)
			)
			(layer "B.SilkS")
		)
		(fp_line
			(start -1.524 0.762)
			(end 1.524 0.762)
			(stroke
				(width 0.1524)
				(type default)
			)
			(layer "B.SilkS")
		)
		(fp_line
			(start 1.1049 -0.724916)
			(end 1.1049 0.724916)
			(stroke
				(width 0.1)
				(type default)
			)
			(layer "B.Fab")
		)
		(fp_line
			(start -1.1049 -0.724916)
			(end 1.1049 -0.724916)
			(stroke
				(width 0.1)
				(type default)
			)
			(layer "B.Fab")
		)
		(fp_line
			(start 1.1049 0.724916)
			(end -1.1049 0.724916)
			(stroke
				(width 0.1)
				(type default)
			)
			(layer "B.Fab")
		)
		(fp_line
			(start -1.1049 0.724916)
			(end -1.1049 -0.724916)
			(stroke
				(width 0.1)
				(type default)
			)
			(layer "B.Fab")
		)
		(pad "1" smd rect
			(at 0.889 0 90)
			(size 1.016 1.27)
			(layers "B.Cu" "B.Mask" "B.Paste")
			(net "P52V_HSC")
		)
		(pad "2" smd rect
			(at -0.889 0 90)
			(size 1.016 1.27)
			(layers "B.Cu" "B.Mask" "B.Paste")
			(net "GND")
		)
	)
	(footprint ""
		(layer "B.Cu")
		(at 34.417 -64.837056 -90)
		(property "Reference" "PC20"
			(at 0 0 90)
			(layer "B.SilkS")
			(hide yes)
			(effects
				(font
					(size 1.27 1.27)
				)
				(justify mirror)
			)
		)
		(property "Value" ""
			(at 0 0 90)
			(layer "B.Fab")
			(effects
				(font
					(size 1.27 1.27)
				)
				(justify mirror)
			)
		)
		(duplicate_pad_numbers_are_jumpers no)
		(fp_line
			(start -0.7874 0.4064)
			(end 0.7874 0.4064)
			(stroke
				(width 0.1524)
				(type default)
			)
			(layer "B.SilkS")
		)
		(fp_line
			(start 0.7874 0.4064)
			(end 0.7874 -0.4064)
			(stroke
				(width 0.1524)
				(type default)
			)
			(layer "B.SilkS")
		)
		(fp_line
			(start -0.7874 -0.4064)
			(end -0.7874 0.4064)
			(stroke
				(width 0.1524)
				(type default)
			)
			(layer "B.SilkS")
		)
		(fp_line
			(start 0.7874 -0.4064)
			(end -0.7874 -0.4064)
			(stroke
				(width 0.1524)
				(type default)
			)
			(layer "B.SilkS")
		)
		(fp_line
			(start -0.67945 0.3048)
			(end -0.120396 0.3048)
			(stroke
				(width 0.1)
				(type default)
			)
			(layer "B.Fab")
		)
		(fp_line
			(start -0.120396 0.3048)
			(end -0.120396 0.2794)
			(stroke
				(width 0.1)
				(type default)
			)
			(layer "B.Fab")
		)
		(fp_line
			(start 0.12065 0.3048)
			(end 0.67945 0.3048)
			(stroke
				(width 0.1)
				(type default)
			)
			(layer "B.Fab")
		)
		(fp_line
			(start 0.67945 0.3048)
			(end 0.67945 -0.305054)
			(stroke
				(width 0.1)
				(type default)
			)
			(layer "B.Fab")
		)
		(fp_line
			(start -0.120396 0.2794)
			(end 0.12065 0.2794)
			(stroke
				(width 0.1)
				(type default)
			)
			(layer "B.Fab")
		)
		(fp_line
			(start 0.12065 0.2794)
			(end 0.12065 0.3048)
			(stroke
				(width 0.1)
				(type default)
			)
			(layer "B.Fab")
		)
		(fp_line
			(start -0.12065 -0.2794)
			(end -0.12065 -0.3048)
			(stroke
				(width 0.1)
				(type default)
			)
			(layer "B.Fab")
		)
		(fp_line
			(start 0.12065 -0.2794)
			(end -0.12065 -0.2794)
			(stroke
				(width 0.1)
				(type default)
			)
			(layer "B.Fab")
		)
		(fp_line
			(start -0.67945 -0.3048)
			(end -0.67945 0.3048)
			(stroke
				(width 0.1)
				(type default)
			)
			(layer "B.Fab")
		)
		(fp_line
			(start -0.12065 -0.3048)
			(end -0.67945 -0.3048)
			(stroke
				(width 0.1)
				(type default)
			)
			(layer "B.Fab")
		)
		(fp_line
			(start 0.12065 -0.305054)
			(end 0.12065 -0.2794)
			(stroke
				(width 0.1)
				(type default)
			)
			(layer "B.Fab")
		)
		(fp_line
			(start 0.67945 -0.305054)
			(end 0.12065 -0.305054)
			(stroke
				(width 0.1)
				(type default)
			)
			(layer "B.Fab")
		)
		(pad "1" smd circle
			(at 0.40005 0 90)
			(size 0 0)
			(layers "B.Cu" "B.Mask" "B.Paste")
			(net "FAN_3_SS")
		)
		(pad "2" smd circle
			(at -0.40005 0 90)
			(size 0 0)
			(layers "B.Cu" "B.Mask" "B.Paste")
			(net "GND")
		)
	)
	(footprint ""
		(layer "B.Cu")
		(at 15.367 -258.572 90)
		(property "Reference" "PR77"
			(at 0 0 90)
			(layer "B.SilkS")
			(hide yes)
			(effects
				(font
					(size 1.27 1.27)
				)
				(justify mirror)
			)
		)
		(property "Value" ""
			(at 0 0 90)
			(layer "B.Fab")
			(effects
				(font
					(size 1.27 1.27)
				)
				(justify mirror)
			)
		)
		(duplicate_pad_numbers_are_jumpers no)
		(fp_line
			(start 0.7874 -0.4064)
			(end -0.7874 -0.4064)
			(stroke
				(width 0.1524)
				(type default)
			)
			(layer "B.SilkS")
		)
		(fp_line
			(start -0.7874 -0.4064)
			(end -0.7874 0.4064)
			(stroke
				(width 0.1524)
				(type default)
			)
			(layer "B.SilkS")
		)
		(fp_line
			(start 0.7874 0.4064)
			(end 0.7874 -0.4064)
			(stroke
				(width 0.1524)
				(type default)
			)
			(layer "B.SilkS")
		)
		(fp_line
			(start -0.7874 0.4064)
			(end 0.7874 0.4064)
			(stroke
				(width 0.1524)
				(type default)
			)
			(layer "B.SilkS")
		)
		(fp_line
			(start 0.67945 -0.305054)
			(end 0.12065 -0.305054)
			(stroke
				(width 0.1)
				(type default)
			)
			(layer "B.Fab")
		)
		(fp_line
			(start 0.12065 -0.305054)
			(end 0.12065 -0.2794)
			(stroke
				(width 0.1)
				(type default)
			)
			(layer "B.Fab")
		)
		(fp_line
			(start -0.12065 -0.3048)
			(end -0.67945 -0.3048)
			(stroke
				(width 0.1)
				(type default)
			)
			(layer "B.Fab")
		)
		(fp_line
			(start -0.67945 -0.3048)
			(end -0.67945 0.3048)
			(stroke
				(width 0.1)
				(type default)
			)
			(layer "B.Fab")
		)
		(fp_line
			(start 0.12065 -0.2794)
			(end -0.12065 -0.2794)
			(stroke
				(width 0.1)
				(type default)
			)
			(layer "B.Fab")
		)
		(fp_line
			(start -0.12065 -0.2794)
			(end -0.12065 -0.3048)
			(stroke
				(width 0.1)
				(type default)
			)
			(layer "B.Fab")
		)
		(fp_line
			(start 0.12065 0.2794)
			(end 0.12065 0.3048)
			(stroke
				(width 0.1)
				(type default)
			)
			(layer "B.Fab")
		)
		(fp_line
			(start -0.120396 0.2794)
			(end 0.12065 0.2794)
			(stroke
				(width 0.1)
				(type default)
			)
			(layer "B.Fab")
		)
		(fp_line
			(start 0.67945 0.3048)
			(end 0.67945 -0.305054)
			(stroke
				(width 0.1)
				(type default)
			)
			(layer "B.Fab")
		)
		(fp_line
			(start 0.12065 0.3048)
			(end 0.67945 0.3048)
			(stroke
				(width 0.1)
				(type default)
			)
			(layer "B.Fab")
		)
		(fp_line
			(start -0.120396 0.3048)
			(end -0.120396 0.2794)
			(stroke
				(width 0.1)
				(type default)
			)
			(layer "B.Fab")
		)
		(fp_line
			(start -0.67945 0.3048)
			(end -0.120396 0.3048)
			(stroke
				(width 0.1)
				(type default)
			)
			(layer "B.Fab")
		)
		(pad "1" smd circle
			(at 0.40005 0 270)
			(size 0 0)
			(layers "B.Cu" "B.Mask" "B.Paste")
			(net "FAN_7_CLREF")
		)
		(pad "2" smd circle
			(at -0.40005 0 270)
			(size 0 0)
			(layers "B.Cu" "B.Mask" "B.Paste")
			(net "GND")
		)
	)
	(footprint ""
		(layer "B.Cu")
		(at 15.113 -73.971912 90)
		(property "Reference" "PR61"
			(at 0 0 90)
			(layer "B.SilkS")
			(hide yes)
			(effects
				(font
					(size 1.27 1.27)
				)
				(justify mirror)
			)
		)
		(property "Value" ""
			(at 0 0 90)
			(layer "B.Fab")
			(effects
				(font
					(size 1.27 1.27)
				)
				(justify mirror)
			)
		)
		(duplicate_pad_numbers_are_jumpers no)
		(fp_line
			(start 0.7874 -0.4064)
			(end -0.7874 -0.4064)
			(stroke
				(width 0.1524)
				(type default)
			)
			(layer "B.SilkS")
		)
		(fp_line
			(start -0.7874 -0.4064)
			(end -0.7874 0.4064)
			(stroke
				(width 0.1524)
				(type default)
			)
			(layer "B.SilkS")
		)
		(fp_line
			(start 0.7874 0.4064)
			(end 0.7874 -0.4064)
			(stroke
				(width 0.1524)
				(type default)
			)
			(layer "B.SilkS")
		)
		(fp_line
			(start -0.7874 0.4064)
			(end 0.7874 0.4064)
			(stroke
				(width 0.1524)
				(type default)
			)
			(layer "B.SilkS")
		)
		(fp_line
			(start 0.67945 -0.305054)
			(end 0.12065 -0.305054)
			(stroke
				(width 0.1)
				(type default)
			)
			(layer "B.Fab")
		)
		(fp_line
			(start 0.12065 -0.305054)
			(end 0.12065 -0.2794)
			(stroke
				(width 0.1)
				(type default)
			)
			(layer "B.Fab")
		)
		(fp_line
			(start -0.12065 -0.3048)
			(end -0.67945 -0.3048)
			(stroke
				(width 0.1)
				(type default)
			)
			(layer "B.Fab")
		)
		(fp_line
			(start -0.67945 -0.3048)
			(end -0.67945 0.3048)
			(stroke
				(width 0.1)
				(type default)
			)
			(layer "B.Fab")
		)
		(fp_line
			(start 0.12065 -0.2794)
			(end -0.12065 -0.2794)
			(stroke
				(width 0.1)
				(type default)
			)
			(layer "B.Fab")
		)
		(fp_line
			(start -0.12065 -0.2794)
			(end -0.12065 -0.3048)
			(stroke
				(width 0.1)
				(type default)
			)
			(layer "B.Fab")
		)
		(fp_line
			(start 0.12065 0.2794)
			(end 0.12065 0.3048)
			(stroke
				(width 0.1)
				(type default)
			)
			(layer "B.Fab")
		)
		(fp_line
			(start -0.120396 0.2794)
			(end 0.12065 0.2794)
			(stroke
				(width 0.1)
				(type default)
			)
			(layer "B.Fab")
		)
		(fp_line
			(start 0.67945 0.3048)
			(end 0.67945 -0.305054)
			(stroke
				(width 0.1)
				(type default)
			)
			(layer "B.Fab")
		)
		(fp_line
			(start 0.12065 0.3048)
			(end 0.67945 0.3048)
			(stroke
				(width 0.1)
				(type default)
			)
			(layer "B.Fab")
		)
		(fp_line
			(start -0.120396 0.3048)
			(end -0.120396 0.2794)
			(stroke
				(width 0.1)
				(type default)
			)
			(layer "B.Fab")
		)
		(fp_line
			(start -0.67945 0.3048)
			(end -0.120396 0.3048)
			(stroke
				(width 0.1)
				(type default)
			)
			(layer "B.Fab")
		)
		(pad "1" smd circle
			(at 0.40005 0 270)
			(size 0 0)
			(layers "B.Cu" "B.Mask" "B.Paste")
			(net "FAN_5_CLREF")
		)
		(pad "2" smd circle
			(at -0.40005 0 270)
			(size 0 0)
			(layers "B.Cu" "B.Mask" "B.Paste")
			(net "GND")
		)
	)
	(footprint ""
		(layer "B.Cu")
		(at 47.7266 -171.5008)
		(property "Reference" ""
			(at 0 0 0)
			(layer "B.SilkS")
			(hide yes)
			(effects
				(font
					(size 1.27 1.27)
				)
				(justify mirror)
			)
		)
		(property "Value" ""
			(at 0 0 0)
			(layer "B.Fab")
			(effects
				(font
					(size 1.27 1.27)
				)
				(justify mirror)
			)
		)
		(duplicate_pad_numbers_are_jumpers no)
		(pad "1" smd circle
			(at 0 0 180)
			(size 0.9906 0.9906)
			(layers "B.Cu" "B.Mask" "B.Paste")
			(net "Net_124")
		)
		(zone
			(layer "B.Cu")
			(hatch none 0.5)
			(connect_pads
				(clearance 0)
			)
			(min_thickness 0.25)
			(keepout
				(tracks not_allowed)
				(vias allowed)
				(pads allowed)
				(copperpour not_allowed)
				(footprints allowed)
			)
			(placement
				(enabled no)
				(sheetname "")
			)
			(fill
				(thermal_gap 0.5)
				(thermal_bridge_width 0.5)
				(island_removal_mode 0)
			)
			(polygon
				(pts
					(arc
						(start 49.3522 -171.5008)
						(mid 46.101 -171.5008)
						(end 49.3522 -171.5008)
					)
				)
			)
		)
	)
	(footprint ""
		(layer "B.Cu")
		(at 42.037 -258.572 90)
		(property "Reference" "PR9"
			(at 0 0 90)
			(layer "B.SilkS")
			(hide yes)
			(effects
				(font
					(size 1.27 1.27)
				)
				(justify mirror)
			)
		)
		(property "Value" ""
			(at 0 0 90)
			(layer "B.Fab")
			(effects
				(font
					(size 1.27 1.27)
				)
				(justify mirror)
			)
		)
		(duplicate_pad_numbers_are_jumpers no)
		(fp_line
			(start 0.7874 -0.4064)
			(end -0.7874 -0.4064)
			(stroke
				(width 0.1524)
				(type default)
			)
			(layer "B.SilkS")
		)
		(fp_line
			(start -0.7874 -0.4064)
			(end -0.7874 0.4064)
			(stroke
				(width 0.1524)
				(type default)
			)
			(layer "B.SilkS")
		)
		(fp_line
			(start 0.7874 0.4064)
			(end 0.7874 -0.4064)
			(stroke
				(width 0.1524)
				(type default)
			)
			(layer "B.SilkS")
		)
		(fp_line
			(start -0.7874 0.4064)
			(end 0.7874 0.4064)
			(stroke
				(width 0.1524)
				(type default)
			)
			(layer "B.SilkS")
		)
		(fp_line
			(start 0.67945 -0.305054)
			(end 0.12065 -0.305054)
			(stroke
				(width 0.1)
				(type default)
			)
			(layer "B.Fab")
		)
		(fp_line
			(start 0.12065 -0.305054)
			(end 0.12065 -0.2794)
			(stroke
				(width 0.1)
				(type default)
			)
			(layer "B.Fab")
		)
		(fp_line
			(start -0.12065 -0.3048)
			(end -0.67945 -0.3048)
			(stroke
				(width 0.1)
				(type default)
			)
			(layer "B.Fab")
		)
		(fp_line
			(start -0.67945 -0.3048)
			(end -0.67945 0.3048)
			(stroke
				(width 0.1)
				(type default)
			)
			(layer "B.Fab")
		)
		(fp_line
			(start 0.12065 -0.2794)
			(end -0.12065 -0.2794)
			(stroke
				(width 0.1)
				(type default)
			)
			(layer "B.Fab")
		)
		(fp_line
			(start -0.12065 -0.2794)
			(end -0.12065 -0.3048)
			(stroke
				(width 0.1)
				(type default)
			)
			(layer "B.Fab")
		)
		(fp_line
			(start 0.12065 0.2794)
			(end 0.12065 0.3048)
			(stroke
				(width 0.1)
				(type default)
			)
			(layer "B.Fab")
		)
		(fp_line
			(start -0.120396 0.2794)
			(end 0.12065 0.2794)
			(stroke
				(width 0.1)
				(type default)
			)
			(layer "B.Fab")
		)
		(fp_line
			(start 0.67945 0.3048)
			(end 0.67945 -0.305054)
			(stroke
				(width 0.1)
				(type default)
			)
			(layer "B.Fab")
		)
		(fp_line
			(start 0.12065 0.3048)
			(end 0.67945 0.3048)
			(stroke
				(width 0.1)
				(type default)
			)
			(layer "B.Fab")
		)
		(fp_line
			(start -0.120396 0.3048)
			(end -0.120396 0.2794)
			(stroke
				(width 0.1)
				(type default)
			)
			(layer "B.Fab")
		)
		(fp_line
			(start -0.67945 0.3048)
			(end -0.120396 0.3048)
			(stroke
				(width 0.1)
				(type default)
			)
			(layer "B.Fab")
		)
		(pad "1" smd circle
			(at 0.40005 0 270)
			(size 0 0)
			(layers "B.Cu" "B.Mask" "B.Paste")
			(net "FAN_0_CLREF")
		)
		(pad "2" smd circle
			(at -0.40005 0 270)
			(size 0 0)
			(layers "B.Cu" "B.Mask" "B.Paste")
			(net "GND")
		)
	)
)
